(kicad_pcb
	(version 20260206)
	(generator "pcbnew")
	(generator_version "10.0")
	(general
		(thickness 1.6)
		(legacy_teardrops no)
	)
	(paper "A4")
	(title_block
		(title "01162023_DA0F0TEBIF0_F0T_Expander_BD_F_brd_V02_OCP.brd")
		(comment 1 "Grand Teton / footprints 4174-4180 of 9728")
	)
	(layers
		(0 "F.Cu" signal "TOP")
		(4 "In1.Cu" signal "GND")
		(6 "In2.Cu" signal "VCC")
		(8 "In3.Cu" signal "VCC1")
		(10 "In4.Cu" signal "GND1")
		(12 "In5.Cu" signal "IN1")
		(14 "In6.Cu" signal "GND2")
		(16 "In7.Cu" signal "IN2")
		(18 "In8.Cu" signal "GND3")
		(20 "In9.Cu" signal "IN3")
		(22 "In10.Cu" signal "GND4")
		(24 "In11.Cu" signal "IN4")
		(26 "In12.Cu" signal "GND5")
		(28 "In13.Cu" signal "IN5")
		(30 "In14.Cu" signal "GND6")
		(32 "In15.Cu" signal "IN6")
		(34 "In16.Cu" signal "GND7")
		(2 "B.Cu" signal "BOTTOM")
		(9 "F.Adhes" user "F.Adhesive")
		(11 "B.Adhes" user "B.Adhesive")
		(13 "F.Paste" user "Package Geometry/Pastemask Top")
		(15 "B.Paste" user "Package Geometry/Pastemask Bottom")
		(5 "F.SilkS" user "Ref Des/Silkscreen Top")
		(7 "B.SilkS" user "Ref Des/Silkscreen Bottom")
		(1 "F.Mask" user "Board Geometry/Soldermask Top")
		(3 "B.Mask" user "Board Geometry/Soldermask Bottom")
		(17 "Dwgs.User" user "User.Drawings")
		(19 "Cmts.User" user "User.Comments")
		(21 "Eco1.User" user "User.Eco1")
		(23 "Eco2.User" user "User.Eco2")
		(25 "Edge.Cuts" user "Board Geometry/Outline")
		(27 "Margin" user)
		(31 "F.CrtYd" user "Package Geometry/Place Bound Top")
		(29 "B.CrtYd" user "Package Geometry/Place Bound Bottom")
		(35 "F.Fab" user "Ref Des/Assembly Top")
		(33 "B.Fab" user "Ref Des/Assembly Bottom")
	)
	(footprint ""
		(layer "F.Cu")
		(at 453.29602 -371.5258)
		(property "Reference" "R6688"
			(at 0 0 0)
			(layer "F.SilkS")
			(hide yes)
			(effects
				(font
					(size 1.27 1.27)
				)
			)
		)
		(property "Value" ""
			(at 0 0 0)
			(layer "F.Fab")
			(effects
				(font
					(size 1.27 1.27)
				)
			)
		)
		(duplicate_pad_numbers_are_jumpers no)
		(fp_line
			(start -0.7874 -0.4064)
			(end 0.7874 -0.4064)
			(stroke
				(width 0.1524)
				(type default)
			)
			(layer "F.SilkS")
		)
		(fp_line
			(start -0.7874 0.4064)
			(end -0.7874 -0.4064)
			(stroke
				(width 0.1524)
				(type default)
			)
			(layer "F.SilkS")
		)
		(fp_line
			(start 0.7874 -0.4064)
			(end 0.7874 0.4064)
			(stroke
				(width 0.1524)
				(type default)
			)
			(layer "F.SilkS")
		)
		(fp_line
			(start 0.7874 0.4064)
			(end -0.7874 0.4064)
			(stroke
				(width 0.1524)
				(type default)
			)
			(layer "F.SilkS")
		)
		(fp_line
			(start -0.67945 -0.305054)
			(end -0.12065 -0.305054)
			(stroke
				(width 0.1)
				(type default)
			)
			(layer "F.Fab")
		)
		(fp_line
			(start -0.67945 0.3048)
			(end -0.67945 -0.305054)
			(stroke
				(width 0.1)
				(type default)
			)
			(layer "F.Fab")
		)
		(fp_line
			(start -0.12065 -0.305054)
			(end -0.12065 -0.2794)
			(stroke
				(width 0.1)
				(type default)
			)
			(layer "F.Fab")
		)
		(fp_line
			(start -0.12065 -0.2794)
			(end 0.12065 -0.2794)
			(stroke
				(width 0.1)
				(type default)
			)
			(layer "F.Fab")
		)
		(fp_line
			(start -0.12065 0.2794)
			(end -0.12065 0.3048)
			(stroke
				(width 0.1)
				(type default)
			)
			(layer "F.Fab")
		)
		(fp_line
			(start -0.12065 0.3048)
			(end -0.67945 0.3048)
			(stroke
				(width 0.1)
				(type default)
			)
			(layer "F.Fab")
		)
		(fp_line
			(start 0.120396 0.2794)
			(end -0.12065 0.2794)
			(stroke
				(width 0.1)
				(type default)
			)
			(layer "F.Fab")
		)
		(fp_line
			(start 0.120396 0.3048)
			(end 0.120396 0.2794)
			(stroke
				(width 0.1)
				(type default)
			)
			(layer "F.Fab")
		)
		(fp_line
			(start 0.12065 -0.3048)
			(end 0.67945 -0.3048)
			(stroke
				(width 0.1)
				(type default)
			)
			(layer "F.Fab")
		)
		(fp_line
			(start 0.12065 -0.2794)
			(end 0.12065 -0.3048)
			(stroke
				(width 0.1)
				(type default)
			)
			(layer "F.Fab")
		)
		(fp_line
			(start 0.67945 -0.3048)
			(end 0.67945 0.3048)
			(stroke
				(width 0.1)
				(type default)
			)
			(layer "F.Fab")
		)
		(fp_line
			(start 0.67945 0.3048)
			(end 0.120396 0.3048)
			(stroke
				(width 0.1)
				(type default)
			)
			(layer "F.Fab")
		)
		(pad "1" smd circle
			(at -0.40005 0)
			(size 0 0)
			(layers "F.Cu" "F.Mask" "F.Paste")
			(net "GPU_3V3IO_RSVD3_ISO")
		)
		(pad "2" smd circle
			(at 0.40005 0)
			(size 0 0)
			(layers "F.Cu" "F.Mask" "F.Paste")
			(net "GPU_3V3IO_RSVD3")
		)
	)
	(footprint ""
		(layer "F.Cu")
		(at 325.03237 -87.414354 -90)
		(property "Reference" "R6385"
			(at 0 0 270)
			(layer "F.SilkS")
			(hide yes)
			(effects
				(font
					(size 1.27 1.27)
				)
			)
		)
		(property "Value" ""
			(at 0 0 270)
			(layer "F.Fab")
			(effects
				(font
					(size 1.27 1.27)
				)
			)
		)
		(duplicate_pad_numbers_are_jumpers no)
		(fp_line
			(start -0.7874 0.4064)
			(end -0.7874 -0.4064)
			(stroke
				(width 0.1524)
				(type default)
			)
			(layer "F.SilkS")
		)
		(fp_line
			(start 0.7874 0.4064)
			(end -0.7874 0.4064)
			(stroke
				(width 0.1524)
				(type default)
			)
			(layer "F.SilkS")
		)
		(fp_line
			(start -0.7874 -0.4064)
			(end 0.7874 -0.4064)
			(stroke
				(width 0.1524)
				(type default)
			)
			(layer "F.SilkS")
		)
		(fp_line
			(start 0.7874 -0.4064)
			(end 0.7874 0.4064)
			(stroke
				(width 0.1524)
				(type default)
			)
			(layer "F.SilkS")
		)
		(fp_line
			(start -0.67945 0.3048)
			(end -0.67945 -0.305054)
			(stroke
				(width 0.1)
				(type default)
			)
			(layer "F.Fab")
		)
		(fp_line
			(start -0.12065 0.3048)
			(end -0.67945 0.3048)
			(stroke
				(width 0.1)
				(type default)
			)
			(layer "F.Fab")
		)
		(fp_line
			(start 0.120396 0.3048)
			(end 0.120396 0.2794)
			(stroke
				(width 0.1)
				(type default)
			)
			(layer "F.Fab")
		)
		(fp_line
			(start 0.67945 0.3048)
			(end 0.120396 0.3048)
			(stroke
				(width 0.1)
				(type default)
			)
			(layer "F.Fab")
		)
		(fp_line
			(start -0.12065 0.2794)
			(end -0.12065 0.3048)
			(stroke
				(width 0.1)
				(type default)
			)
			(layer "F.Fab")
		)
		(fp_line
			(start 0.120396 0.2794)
			(end -0.12065 0.2794)
			(stroke
				(width 0.1)
				(type default)
			)
			(layer "F.Fab")
		)
		(fp_line
			(start -0.12065 -0.2794)
			(end 0.12065 -0.2794)
			(stroke
				(width 0.1)
				(type default)
			)
			(layer "F.Fab")
		)
		(fp_line
			(start 0.12065 -0.2794)
			(end 0.12065 -0.3048)
			(stroke
				(width 0.1)
				(type default)
			)
			(layer "F.Fab")
		)
		(fp_line
			(start 0.12065 -0.3048)
			(end 0.67945 -0.3048)
			(stroke
				(width 0.1)
				(type default)
			)
			(layer "F.Fab")
		)
		(fp_line
			(start 0.67945 -0.3048)
			(end 0.67945 0.3048)
			(stroke
				(width 0.1)
				(type default)
			)
			(layer "F.Fab")
		)
		(fp_line
			(start -0.67945 -0.305054)
			(end -0.12065 -0.305054)
			(stroke
				(width 0.1)
				(type default)
			)
			(layer "F.Fab")
		)
		(fp_line
			(start -0.12065 -0.305054)
			(end -0.12065 -0.2794)
			(stroke
				(width 0.1)
				(type default)
			)
			(layer "F.Fab")
		)
		(pad "1" smd circle
			(at -0.40005 0 270)
			(size 0 0)
			(layers "F.Cu" "F.Mask" "F.Paste")
			(net "SMB_BMC_9FGL0451E_S3_SDA")
		)
		(pad "2" smd circle
			(at 0.40005 0 270)
			(size 0 0)
			(layers "F.Cu" "F.Mask" "F.Paste")
			(net "SMB_ISO_CB_SDA")
		)
	)
	(footprint ""
		(layer "F.Cu")
		(at 215.464136 -181.613556 -90)
		(property "Reference" "C3625"
			(at 0 0 270)
			(layer "F.SilkS")
			(hide yes)
			(effects
				(font
					(size 1.27 1.27)
				)
			)
		)
		(property "Value" ""
			(at 0 0 270)
			(layer "F.Fab")
			(effects
				(font
					(size 1.27 1.27)
				)
			)
		)
		(duplicate_pad_numbers_are_jumpers no)
		(fp_line
			(start -0.7874 0.4064)
			(end -0.7874 -0.4064)
			(stroke
				(width 0.1524)
				(type default)
			)
			(layer "F.SilkS")
		)
		(fp_line
			(start 0.7874 0.4064)
			(end -0.7874 0.4064)
			(stroke
				(width 0.1524)
				(type default)
			)
			(layer "F.SilkS")
		)
		(fp_line
			(start -0.7874 -0.4064)
			(end 0.7874 -0.4064)
			(stroke
				(width 0.1524)
				(type default)
			)
			(layer "F.SilkS")
		)
		(fp_line
			(start 0.7874 -0.4064)
			(end 0.7874 0.4064)
			(stroke
				(width 0.1524)
				(type default)
			)
			(layer "F.SilkS")
		)
		(fp_line
			(start -0.67945 0.3048)
			(end -0.67945 -0.305054)
			(stroke
				(width 0.1)
				(type default)
			)
			(layer "F.Fab")
		)
		(fp_line
			(start -0.12065 0.3048)
			(end -0.67945 0.3048)
			(stroke
				(width 0.1)
				(type default)
			)
			(layer "F.Fab")
		)
		(fp_line
			(start 0.120396 0.3048)
			(end 0.120396 0.2794)
			(stroke
				(width 0.1)
				(type default)
			)
			(layer "F.Fab")
		)
		(fp_line
			(start 0.67945 0.3048)
			(end 0.120396 0.3048)
			(stroke
				(width 0.1)
				(type default)
			)
			(layer "F.Fab")
		)
		(fp_line
			(start -0.12065 0.2794)
			(end -0.12065 0.3048)
			(stroke
				(width 0.1)
				(type default)
			)
			(layer "F.Fab")
		)
		(fp_line
			(start 0.120396 0.2794)
			(end -0.12065 0.2794)
			(stroke
				(width 0.1)
				(type default)
			)
			(layer "F.Fab")
		)
		(fp_line
			(start -0.12065 -0.2794)
			(end 0.12065 -0.2794)
			(stroke
				(width 0.1)
				(type default)
			)
			(layer "F.Fab")
		)
		(fp_line
			(start 0.12065 -0.2794)
			(end 0.12065 -0.3048)
			(stroke
				(width 0.1)
				(type default)
			)
			(layer "F.Fab")
		)
		(fp_line
			(start 0.12065 -0.3048)
			(end 0.67945 -0.3048)
			(stroke
				(width 0.1)
				(type default)
			)
			(layer "F.Fab")
		)
		(fp_line
			(start 0.67945 -0.3048)
			(end 0.67945 0.3048)
			(stroke
				(width 0.1)
				(type default)
			)
			(layer "F.Fab")
		)
		(fp_line
			(start -0.67945 -0.305054)
			(end -0.12065 -0.305054)
			(stroke
				(width 0.1)
				(type default)
			)
			(layer "F.Fab")
		)
		(fp_line
			(start -0.12065 -0.305054)
			(end -0.12065 -0.2794)
			(stroke
				(width 0.1)
				(type default)
			)
			(layer "F.Fab")
		)
		(pad "1" smd circle
			(at -0.40005 0 270)
			(size 0 0)
			(layers "F.Cu" "F.Mask" "F.Paste")
			(net "P3V3_AUX")
		)
		(pad "2" smd circle
			(at 0.40005 0 270)
			(size 0 0)
			(layers "F.Cu" "F.Mask" "F.Paste")
			(net "GND")
		)
	)
	(footprint ""
		(layer "F.Cu")
		(at 433.00904 -27.04973 180)
		(property "Reference" "C2778"
			(at 0 0 180)
			(layer "F.SilkS")
			(hide yes)
			(effects
				(font
					(size 1.27 1.27)
				)
			)
		)
		(property "Value" ""
			(at 0 0 180)
			(layer "F.Fab")
			(effects
				(font
					(size 1.27 1.27)
				)
			)
		)
		(duplicate_pad_numbers_are_jumpers no)
		(fp_line
			(start 0.7874 0.4064)
			(end -0.7874 0.4064)
			(stroke
				(width 0.1524)
				(type default)
			)
			(layer "F.SilkS")
		)
		(fp_line
			(start 0.7874 -0.4064)
			(end 0.7874 0.4064)
			(stroke
				(width 0.1524)
				(type default)
			)
			(layer "F.SilkS")
		)
		(fp_line
			(start -0.7874 0.4064)
			(end -0.7874 -0.4064)
			(stroke
				(width 0.1524)
				(type default)
			)
			(layer "F.SilkS")
		)
		(fp_line
			(start -0.7874 -0.4064)
			(end 0.7874 -0.4064)
			(stroke
				(width 0.1524)
				(type default)
			)
			(layer "F.SilkS")
		)
		(fp_line
			(start 0.67945 0.3048)
			(end 0.120396 0.3048)
			(stroke
				(width 0.1)
				(type default)
			)
			(layer "F.Fab")
		)
		(fp_line
			(start 0.67945 -0.3048)
			(end 0.67945 0.3048)
			(stroke
				(width 0.1)
				(type default)
			)
			(layer "F.Fab")
		)
		(fp_line
			(start 0.12065 -0.2794)
			(end 0.12065 -0.3048)
			(stroke
				(width 0.1)
				(type default)
			)
			(layer "F.Fab")
		)
		(fp_line
			(start 0.12065 -0.3048)
			(end 0.67945 -0.3048)
			(stroke
				(width 0.1)
				(type default)
			)
			(layer "F.Fab")
		)
		(fp_line
			(start 0.120396 0.3048)
			(end 0.120396 0.2794)
			(stroke
				(width 0.1)
				(type default)
			)
			(layer "F.Fab")
		)
		(fp_line
			(start 0.120396 0.2794)
			(end -0.12065 0.2794)
			(stroke
				(width 0.1)
				(type default)
			)
			(layer "F.Fab")
		)
		(fp_line
			(start -0.12065 0.3048)
			(end -0.67945 0.3048)
			(stroke
				(width 0.1)
				(type default)
			)
			(layer "F.Fab")
		)
		(fp_line
			(start -0.12065 0.2794)
			(end -0.12065 0.3048)
			(stroke
				(width 0.1)
				(type default)
			)
			(layer "F.Fab")
		)
		(fp_line
			(start -0.12065 -0.2794)
			(end 0.12065 -0.2794)
			(stroke
				(width 0.1)
				(type default)
			)
			(layer "F.Fab")
		)
		(fp_line
			(start -0.12065 -0.305054)
			(end -0.12065 -0.2794)
			(stroke
				(width 0.1)
				(type default)
			)
			(layer "F.Fab")
		)
		(fp_line
			(start -0.67945 0.3048)
			(end -0.67945 -0.305054)
			(stroke
				(width 0.1)
				(type default)
			)
			(layer "F.Fab")
		)
		(fp_line
			(start -0.67945 -0.305054)
			(end -0.12065 -0.305054)
			(stroke
				(width 0.1)
				(type default)
			)
			(layer "F.Fab")
		)
		(pad "1" smd circle
			(at -0.40005 0 180)
			(size 0 0)
			(layers "F.Cu" "F.Mask" "F.Paste")
			(net "PRSNT_SSD15_R_N")
		)
		(pad "2" smd circle
			(at 0.40005 0 180)
			(size 0 0)
			(layers "F.Cu" "F.Mask" "F.Paste")
			(net "GND")
		)
	)
	(footprint ""
		(layer "F.Cu")
		(at 400.543776 -49.95291 180)
		(property "Reference" "R654"
			(at 0 0 180)
			(layer "F.SilkS")
			(hide yes)
			(effects
				(font
					(size 1.27 1.27)
				)
			)
		)
		(property "Value" ""
			(at 0 0 180)
			(layer "F.Fab")
			(effects
				(font
					(size 1.27 1.27)
				)
			)
		)
		(duplicate_pad_numbers_are_jumpers no)
		(fp_line
			(start 0.7874 0.4064)
			(end -0.7874 0.4064)
			(stroke
				(width 0.1524)
				(type default)
			)
			(layer "F.SilkS")
		)
		(fp_line
			(start 0.7874 -0.4064)
			(end 0.7874 0.4064)
			(stroke
				(width 0.1524)
				(type default)
			)
			(layer "F.SilkS")
		)
		(fp_line
			(start -0.7874 0.4064)
			(end -0.7874 -0.4064)
			(stroke
				(width 0.1524)
				(type default)
			)
			(layer "F.SilkS")
		)
		(fp_line
			(start -0.7874 -0.4064)
			(end 0.7874 -0.4064)
			(stroke
				(width 0.1524)
				(type default)
			)
			(layer "F.SilkS")
		)
		(fp_line
			(start 0.67945 0.3048)
			(end 0.120396 0.3048)
			(stroke
				(width 0.1)
				(type default)
			)
			(layer "F.Fab")
		)
		(fp_line
			(start 0.67945 -0.3048)
			(end 0.67945 0.3048)
			(stroke
				(width 0.1)
				(type default)
			)
			(layer "F.Fab")
		)
		(fp_line
			(start 0.12065 -0.2794)
			(end 0.12065 -0.3048)
			(stroke
				(width 0.1)
				(type default)
			)
			(layer "F.Fab")
		)
		(fp_line
			(start 0.12065 -0.3048)
			(end 0.67945 -0.3048)
			(stroke
				(width 0.1)
				(type default)
			)
			(layer "F.Fab")
		)
		(fp_line
			(start 0.120396 0.3048)
			(end 0.120396 0.2794)
			(stroke
				(width 0.1)
				(type default)
			)
			(layer "F.Fab")
		)
		(fp_line
			(start 0.120396 0.2794)
			(end -0.12065 0.2794)
			(stroke
				(width 0.1)
				(type default)
			)
			(layer "F.Fab")
		)
		(fp_line
			(start -0.12065 0.3048)
			(end -0.67945 0.3048)
			(stroke
				(width 0.1)
				(type default)
			)
			(layer "F.Fab")
		)
		(fp_line
			(start -0.12065 0.2794)
			(end -0.12065 0.3048)
			(stroke
				(width 0.1)
				(type default)
			)
			(layer "F.Fab")
		)
		(fp_line
			(start -0.12065 -0.2794)
			(end 0.12065 -0.2794)
			(stroke
				(width 0.1)
				(type default)
			)
			(layer "F.Fab")
		)
		(fp_line
			(start -0.12065 -0.305054)
			(end -0.12065 -0.2794)
			(stroke
				(width 0.1)
				(type default)
			)
			(layer "F.Fab")
		)
		(fp_line
			(start -0.67945 0.3048)
			(end -0.67945 -0.305054)
			(stroke
				(width 0.1)
				(type default)
			)
			(layer "F.Fab")
		)
		(fp_line
			(start -0.67945 -0.305054)
			(end -0.12065 -0.305054)
			(stroke
				(width 0.1)
				(type default)
			)
			(layer "F.Fab")
		)
		(pad "1" smd circle
			(at -0.40005 0 180)
			(size 0 0)
			(layers "F.Cu" "F.Mask" "F.Paste")
			(net "SMB_BIC_I2C6_MUX_SSD_8_15_ADC_R_SCL")
		)
		(pad "2" smd circle
			(at 0.40005 0 180)
			(size 0 0)
			(layers "F.Cu" "F.Mask" "F.Paste")
			(net "SMB_SSD13_ADC_SCL")
		)
	)
	(footprint ""
		(layer "F.Cu")
		(at 387.580632 -121.005346)
		(property "Reference" "C678"
			(at 0 0 0)
			(layer "F.SilkS")
			(hide yes)
			(effects
				(font
					(size 1.27 1.27)
				)
			)
		)
		(property "Value" ""
			(at 0 0 0)
			(layer "F.Fab")
			(effects
				(font
					(size 1.27 1.27)
				)
			)
		)
		(duplicate_pad_numbers_are_jumpers no)
		(fp_line
			(start -0.299974 -0.150114)
			(end 0.299974 -0.150114)
			(stroke
				(width 0.1)
				(type default)
			)
			(layer "F.Fab")
		)
		(fp_line
			(start -0.299974 0.150114)
			(end -0.299974 -0.150114)
			(stroke
				(width 0.1)
				(type default)
			)
			(layer "F.Fab")
		)
		(fp_line
			(start 0.299974 -0.150114)
			(end 0.299974 0.150114)
			(stroke
				(width 0.1)
				(type default)
			)
			(layer "F.Fab")
		)
		(fp_line
			(start 0.299974 0.150114)
			(end -0.299974 0.150114)
			(stroke
				(width 0.1)
				(type default)
			)
			(layer "F.Fab")
		)
		(pad "1" smd rect
			(at -0.2667 0)
			(size 0.3048 0.381)
			(layers "F.Cu" "F.Mask" "F.Paste")
			(net "P5E_PEX3_STN1_TX_DN<25>")
		)
		(pad "2" smd rect
			(at 0.2667 0)
			(size 0.3048 0.381)
			(layers "F.Cu" "F.Mask" "F.Paste")
			(net "P5E_PEX3_STN1_TX_C_DN<25>")
		)
	)
	(footprint ""
		(layer "F.Cu")
		(at 133.599428 -350.098614 90)
		(property "Reference" "C2253"
			(at 0 0 90)
			(layer "F.SilkS")
			(hide yes)
			(effects
				(font
					(size 1.27 1.27)
				)
			)
		)
		(property "Value" ""
			(at 0 0 90)
			(layer "F.Fab")
			(effects
				(font
					(size 1.27 1.27)
				)
			)
		)
		(duplicate_pad_numbers_are_jumpers no)
		(fp_line
			(start 0.299974 -0.150114)
			(end 0.299974 0.150114)
			(stroke
				(width 0.1)
				(type default)
			)
			(layer "F.Fab")
		)
		(fp_line
			(start -0.299974 -0.150114)
			(end 0.299974 -0.150114)
			(stroke
				(width 0.1)
				(type default)
			)
			(layer "F.Fab")
		)
		(fp_line
			(start 0.299974 0.150114)
			(end -0.299974 0.150114)
			(stroke
				(width 0.1)
				(type default)
			)
			(layer "F.Fab")
		)
		(fp_line
			(start -0.299974 0.150114)
			(end -0.299974 -0.150114)
			(stroke
				(width 0.1)
				(type default)
			)
			(layer "F.Fab")
		)
		(pad "1" smd rect
			(at -0.2667 0 90)
			(size 0.3048 0.381)
			(layers "F.Cu" "F.Mask" "F.Paste")
			(net "P5E_PEX1_STN5_TX_DP<90>")
		)
		(pad "2" smd rect
			(at 0.2667 0 90)
			(size 0.3048 0.381)
			(layers "F.Cu" "F.Mask" "F.Paste")
			(net "P5E_PEX1_STN5_TX_C_DP<90>")
		)
	)
)
